(kicad_pcb
	(version 20240108)
	(generator "pcbnew")
	(generator_version "8.0")
	(general
		(thickness 1.62)
		(legacy_teardrops no)
	)
	(paper "A4")
	(title_block
		(title "Jetson Orin Baseboard")
		(date "2025-03-12")
		(rev "1.3.4")
		(company "Antmicro Ltd")
		(comment 1 "www.antmicro.com")
		(comment 9 "footprints 205-207 of 677")
	)
	(layers
		(0 "F.Cu" signal)
		(1 "In1.Cu" signal)
		(2 "In2.Cu" signal)
		(3 "In3.Cu" signal)
		(4 "In4.Cu" jumper)
		(5 "In5.Cu" signal)
		(6 "In6.Cu" signal)
		(31 "B.Cu" signal)
		(32 "B.Adhes" user "B.Adhesive")
		(33 "F.Adhes" user "F.Adhesive")
		(34 "B.Paste" user)
		(35 "F.Paste" user)
		(36 "B.SilkS" user "B.Silkscreen")
		(37 "F.SilkS" user "F.Silkscreen")
		(38 "B.Mask" user)
		(39 "F.Mask" user)
		(40 "Dwgs.User" user "User.Drawings")
		(41 "Cmts.User" user "User.Comments")
		(42 "Eco1.User" user "User.Eco1")
		(43 "Eco2.User" user "User.Eco2")
		(44 "Edge.Cuts" user)
		(45 "Margin" user)
		(46 "B.CrtYd" user "B.Courtyard")
		(47 "F.CrtYd" user "F.Courtyard")
		(48 "B.Fab" user)
		(49 "F.Fab" user)
	)
	(footprint "antmicro-footprints:C_Pol_EIA-X"
		(layer "F.Cu")
		(at 63.505 83.59)
		(property "Reference" "C1"
			(at -5.995 1.29 0)
			(layer "F.SilkS")
			(effects
				(font
					(size 0.7 0.7)
					(thickness 0.15)
				)
				(justify left bottom)
			)
		)
		(property "Value" "C_Pol_100u_25V_KEMET-T521-D-107"
			(at 0 3.3 0)
			(layer "F.Fab")
			(effects
				(font
					(size 0.7 0.7)
					(thickness 0.15)
				)
				(justify left bottom)
			)
		)
		(property "Footprint" "antmicro-footprints:C_Pol_EIA-X"
			(at 0 0 0)
			(layer "F.Fab")
			(hide yes)
			(effects
				(font
					(size 1.27 1.27)
					(thickness 0.15)
				)
			)
		)
		(property "Datasheet" "https://content.kemet.com/datasheets/KEM_T2076_T52X-530.pdf"
			(at 0 0 0)
			(layer "F.Fab")
			(hide yes)
			(effects
				(font
					(size 1.27 1.27)
					(thickness 0.15)
				)
			)
		)
		(property "Description" "Surface Mount Tantalum Capacitor, 100 µF, 25 V, 2917 [7343 Metric], ± 20%, 0.04 ohm"
			(at 0 0 0)
			(layer "F.Fab")
			(hide yes)
			(effects
				(font
					(size 1.27 1.27)
					(thickness 0.15)
				)
			)
		)
		(property "Val" "100u"
			(at 0 0 0)
			(unlocked yes)
			(layer "F.Fab")
			(hide yes)
			(effects
				(font
					(size 1 1)
					(thickness 0.15)
				)
			)
		)
		(property "MPN" "T521D107M025ATE040"
			(at 0 0 0)
			(unlocked yes)
			(layer "F.Fab")
			(hide yes)
			(effects
				(font
					(size 1 1)
					(thickness 0.15)
				)
			)
		)
		(property "Manufacturer" "KEMET"
			(at 0 0 0)
			(unlocked yes)
			(layer "F.Fab")
			(hide yes)
			(effects
				(font
					(size 1 1)
					(thickness 0.15)
				)
			)
		)
		(property "License" "Apache-2.0"
			(at 0 0 0)
			(unlocked yes)
			(layer "F.Fab")
			(hide yes)
			(effects
				(font
					(size 1 1)
					(thickness 0.15)
				)
			)
		)
		(property "Author" "Antmicro"
			(at 0 0 0)
			(unlocked yes)
			(layer "F.Fab")
			(hide yes)
			(effects
				(font
					(size 1 1)
					(thickness 0.15)
				)
			)
		)
		(property "Voltage" "25V"
			(at 0 0 0)
			(unlocked yes)
			(layer "F.Fab")
			(hide yes)
			(effects
				(font
					(size 1 1)
					(thickness 0.15)
				)
			)
		)
		(property "Dielectric" "template_dielectric"
			(at 0 0 0)
			(unlocked yes)
			(layer "F.Fab")
			(hide yes)
			(effects
				(font
					(size 1 1)
					(thickness 0.15)
				)
			)
		)
		(sheetname "SoM")
		(sheetfile "som.kicad_sch")
		(attr smd)
		(fp_line
			(start -4.5 -1.8)
			(end -4 -1.8)
			(stroke
				(width 0.15)
				(type solid)
			)
			(layer "F.SilkS")
		)
		(fp_line
			(start -4.25 -2.05)
			(end -4.25 -1.551)
			(stroke
				(width 0.15)
				(type solid)
			)
			(layer "F.SilkS")
		)
		(fp_line
			(start -3.6 -2.2)
			(end 3.6 -2.2)
			(stroke
				(width 0.15)
				(type solid)
			)
			(layer "F.SilkS")
		)
		(fp_line
			(start -3.6 -1.44)
			(end -3.6 -2.2)
			(stroke
				(width 0.15)
				(type solid)
			)
			(layer "F.SilkS")
		)
		(fp_line
			(start -3.6 2.2)
			(end -3.6 1.44)
			(stroke
				(width 0.15)
				(type solid)
			)
			(layer "F.SilkS")
		)
		(fp_line
			(start -3.6 2.2)
			(end 3.6 2.2)
			(stroke
				(width 0.15)
				(type solid)
			)
			(layer "F.SilkS")
		)
		(fp_line
			(start 3.6 -1.44)
			(end 3.6 -2.2)
			(stroke
				(width 0.15)
				(type solid)
			)
			(layer "F.SilkS")
		)
		(fp_line
			(start 3.6 2.2)
			(end 3.6 1.44)
			(stroke
				(width 0.15)
				(type solid)
			)
			(layer "F.SilkS")
		)
		(fp_line
			(start -4.7 -1.4)
			(end -4.7 1.45)
			(stroke
				(width 0.05)
				(type solid)
			)
			(layer "F.CrtYd")
		)
		(fp_line
			(start -4.7 -1.4)
			(end -3.75 -1.4)
			(stroke
				(width 0.05)
				(type solid)
			)
			(layer "F.CrtYd")
		)
		(fp_line
			(start -3.75 -2.4)
			(end -3.75 -1.4)
			(stroke
				(width 0.05)
				(type solid)
			)
			(layer "F.CrtYd")
		)
		(fp_line
			(start -3.75 -2.4)
			(end 3.8 -2.4)
			(stroke
				(width 0.05)
				(type solid)
			)
			(layer "F.CrtYd")
		)
		(fp_line
			(start -3.75 1.45)
			(end -4.7 1.45)
			(stroke
				(width 0.05)
				(type solid)
			)
			(layer "F.CrtYd")
		)
		(fp_line
			(start -3.75 1.45)
			(end -3.75 2.4)
			(stroke
				(width 0.05)
				(type solid)
			)
			(layer "F.CrtYd")
		)
		(fp_line
			(start -3.75 2.4)
			(end 3.8 2.4)
			(stroke
				(width 0.05)
				(type solid)
			)
			(layer "F.CrtYd")
		)
		(fp_line
			(start 3.8 -1.45)
			(end 3.8 -2.4)
			(stroke
				(width 0.05)
				(type solid)
			)
			(layer "F.CrtYd")
		)
		(fp_line
			(start 3.8 -1.45)
			(end 4.75 -1.45)
			(stroke
				(width 0.05)
				(type solid)
			)
			(layer "F.CrtYd")
		)
		(fp_line
			(start 3.8 2.4)
			(end 3.8 1.4)
			(stroke
				(width 0.05)
				(type solid)
			)
			(layer "F.CrtYd")
		)
		(fp_line
			(start 4.75 1.4)
			(end 3.8 1.4)
			(stroke
				(width 0.05)
				(type solid)
			)
			(layer "F.CrtYd")
		)
		(fp_line
			(start 4.75 1.4)
			(end 4.75 -1.45)
			(stroke
				(width 0.05)
				(type solid)
			)
			(layer "F.CrtYd")
		)
		(fp_line
			(start -3.799 -2.3)
			(end 3.799 -2.3)
			(stroke
				(width 0.15)
				(type solid)
			)
			(layer "F.Fab")
		)
		(fp_line
			(start -3.799 2.3)
			(end -3.799 -2.3)
			(stroke
				(width 0.15)
				(type solid)
			)
			(layer "F.Fab")
		)
		(fp_line
			(start 3.799 -2.3)
			(end 3.799 2.3)
			(stroke
				(width 0.15)
				(type solid)
			)
			(layer "F.Fab")
		)
		(fp_line
			(start 3.799 2.3)
			(end -3.799 2.3)
			(stroke
				(width 0.15)
				(type solid)
			)
			(layer "F.Fab")
		)
		(fp_text user "License: Apache-2.0"
			(at -4.5 6.79 0)
			(layer "F.Fab")
			(hide yes)
			(effects
				(font
					(size 0.7 0.7)
					(thickness 0.15)
				)
				(justify left bottom)
			)
		)
		(fp_text user "Author: Antmicro"
			(at -4.5 5.59 0)
			(layer "F.Fab")
			(hide yes)
			(effects
				(font
					(size 0.7 0.7)
					(thickness 0.15)
				)
				(justify left bottom)
			)
		)
		(fp_text user "${REFERENCE}"
			(at -4.5 4.39 0)
			(layer "F.Fab")
			(hide yes)
			(effects
				(font
					(size 0.7 0.7)
					(thickness 0.15)
				)
				(justify left bottom)
			)
		)
		(pad "1" smd roundrect
			(at -3.25 0)
			(size 2.5 2.33)
			(layers "F.Cu" "F.Paste" "F.Mask")
			(roundrect_rratio 0.1)
			(net 438 "/SoM/SoM_VIN")
			(pintype "passive")
		)
		(pad "2" smd roundrect
			(at 3.25 0)
			(size 2.5 2.33)
			(layers "F.Cu" "F.Paste" "F.Mask")
			(roundrect_rratio 0.1)
			(net 1 "GND")
			(pintype "passive")
		)
	)
	(footprint "antmicro-footprints:R_0402_1005Metric"
		(layer "F.Cu")
		(at 85.4 115.8)
		(descr "Resistor SMD 0402")
		(tags "resistor SMD 0402")
		(property "Reference" "R227"
			(at -3.96 3.79 0)
			(layer "F.SilkS")
			(effects
				(font
					(size 0.7 0.7)
					(thickness 0.15)
				)
				(justify left bottom)
			)
		)
		(property "Value" "R_2k2_0402"
			(at 0 1.4 0)
			(layer "F.Fab")
			(effects
				(font
					(size 0.7 0.7)
					(thickness 0.15)
				)
				(justify left bottom)
			)
		)
		(property "Footprint" "antmicro-footprints:R_0402_1005Metric"
			(at 0 0 0)
			(layer "F.Fab")
			(hide yes)
			(effects
				(font
					(size 1.27 1.27)
					(thickness 0.15)
				)
			)
		)
		(property "Datasheet" "https://www.bourns.com/docs/product-datasheets/cr.pdf"
			(at 0 0 0)
			(layer "F.Fab")
			(hide yes)
			(effects
				(font
					(size 1.27 1.27)
					(thickness 0.15)
				)
			)
		)
		(property "Author" "Antmicro"
			(at 0 0 0)
			(layer "F.Fab")
			(hide yes)
			(effects
				(font
					(size 1 1)
					(thickness 0.15)
				)
			)
		)
		(property "License" "Apache-2.0"
			(at 0 0 0)
			(layer "F.Fab")
			(hide yes)
			(effects
				(font
					(size 1 1)
					(thickness 0.15)
				)
			)
		)
		(property "MPN" "CR0402-FX-2201GLF"
			(at 0 0 0)
			(layer "F.Fab")
			(hide yes)
			(effects
				(font
					(size 1 1)
					(thickness 0.15)
				)
			)
		)
		(property "Manufacturer" "Bourns"
			(at 0 0 0)
			(layer "F.Fab")
			(hide yes)
			(effects
				(font
					(size 1 1)
					(thickness 0.15)
				)
			)
		)
		(property "Tolerance" "1%"
			(at 0 0 0)
			(layer "F.Fab")
			(hide yes)
			(effects
				(font
					(size 1 1)
					(thickness 0.15)
				)
			)
		)
		(property "Val" "2k2"
			(at 0 0 0)
			(layer "F.Fab")
			(hide yes)
			(effects
				(font
					(size 1 1)
					(thickness 0.15)
				)
			)
		)
		(sheetname "HDMI")
		(sheetfile "hdmi.kicad_sch")
		(attr smd)
		(fp_rect
			(start -0.925 -0.47)
			(end 0.925 0.47)
			(stroke
				(width 0.05)
				(type default)
			)
			(fill none)
			(layer "F.CrtYd")
		)
		(fp_rect
			(start -0.5 -0.25)
			(end 0.5 0.25)
			(stroke
				(width 0.15)
				(type solid)
			)
			(fill none)
			(layer "F.Fab")
		)
		(fp_text user "License: Apache-2.0"
			(at -0.95 5.169 0)
			(layer "F.Fab")
			(hide yes)
			(effects
				(font
					(size 0.7 0.7)
					(thickness 0.15)
				)
				(justify left bottom)
			)
		)
		(fp_text user "Author: Antmicro"
			(at -0.95 4.169 0)
			(layer "F.Fab")
			(hide yes)
			(effects
				(font
					(size 0.7 0.7)
					(thickness 0.15)
				)
				(justify left bottom)
			)
		)
		(fp_text user "${REFERENCE}"
			(at -0.95 3.168 0)
			(layer "F.Fab")
			(hide yes)
			(effects
				(font
					(size 0.7 0.7)
					(thickness 0.15)
				)
				(justify left bottom)
			)
		)
		(pad "1" smd roundrect
			(at -0.48 0)
			(size 0.59 0.64)
			(layers "F.Cu" "F.Paste" "F.Mask")
			(roundrect_rratio 0.25)
			(net 1 "GND")
			(pintype "passive")
		)
		(pad "2" smd roundrect
			(at 0.48 0)
			(size 0.59 0.64)
			(layers "F.Cu" "F.Paste" "F.Mask")
			(roundrect_rratio 0.25)
			(net 529 "/HDMI/HDMI_HPD_5V")
			(pintype "passive")
		)
	)
	(footprint "antmicro-footprints:SOT-523"
		(layer "F.Cu")
		(at 136.3 121.34 180)
		(property "Reference" "Q9"
			(at -2.05 -0.52 -90)
			(layer "F.SilkS")
			(effects
				(font
					(size 0.7 0.7)
					(thickness 0.15)
				)
				(justify left bottom)
			)
		)
		(property "Value" "PJE138K"
			(at 0.1 1.824 180)
			(layer "F.Fab")
			(effects
				(font
					(size 0.7 0.7)
					(thickness 0.15)
				)
				(justify left bottom)
			)
		)
		(property "Footprint" "antmicro-footprints:SOT-523"
			(at 0 0 180)
			(layer "F.Fab")
			(hide yes)
			(effects
				(font
					(size 1.27 1.27)
					(thickness 0.15)
				)
			)
		)
		(property "Datasheet" "https://www.mouser.com/datasheet/2/1057/PJE138K-1876698.pdf"
			(at 0 0 180)
			(layer "F.Fab")
			(hide yes)
			(effects
				(font
					(size 1.27 1.27)
					(thickness 0.15)
				)
			)
		)
		(property "Author" "Antmicro"
			(at 272.6 242.68 0)
			(layer "F.Fab")
			(hide yes)
			(effects
				(font
					(size 1 1)
					(thickness 0.15)
				)
			)
		)
		(property "License" "Apache-2.0"
			(at 272.6 242.68 0)
			(layer "F.Fab")
			(hide yes)
			(effects
				(font
					(size 1 1)
					(thickness 0.15)
				)
			)
		)
		(property "MPN" "PJE138K_R1_00001"
			(at 272.6 242.68 0)
			(layer "F.Fab")
			(hide yes)
			(effects
				(font
					(size 1 1)
					(thickness 0.15)
				)
			)
		)
		(property "Manufacturer" "PANJIT"
			(at 272.6 242.68 0)
			(layer "F.Fab")
			(hide yes)
			(effects
				(font
					(size 1 1)
					(thickness 0.15)
				)
			)
		)
		(sheetname "Peripherals")
		(sheetfile "peripherals.kicad_sch")
		(attr smd)
		(fp_line
			(start -0.277 -0.551)
			(end -0.277 -0.75)
			(stroke
				(width 0.15)
				(type solid)
			)
			(layer "F.SilkS")
		)
		(fp_line
			(start -0.725 -0.551)
			(end -0.277 -0.551)
			(stroke
				(width 0.15)
				(type solid)
			)
			(layer "F.SilkS")
		)
		(fp_line
			(start -0.927 -0.051)
			(end -0.927 -0.351)
			(stroke
				(width 0.15)
				(type solid)
			)
			(layer "F.SilkS")
		)
		(fp_line
			(start -0.927 -0.351)
			(end -0.725 -0.551)
			(stroke
				(width 0.15)
				(type solid)
			)
			(layer "F.SilkS")
		)
		(fp_circle
			(center -0.9652 0.9652)
			(end -0.9152 0.9652)
			(stroke
				(width 0.15)
				(type solid)
			)
			(fill solid)
			(layer "F.SilkS")
		)
		(fp_line
			(start 1.1 -1.16)
			(end 1.1 1.15)
			(stroke
				(width 0.05)
				(type solid)
			)
			(layer "F.CrtYd")
		)
		(fp_line
			(start -1.12 1.15)
			(end 1.1 1.15)
			(stroke
				(width 0.05)
				(type solid)
			)
			(layer "F.CrtYd")
		)
		(fp_line
			(start -1.12 -1.16)
			(end 1.1 -1.16)
			(stroke
				(width 0.05)
				(type solid)
			)
			(layer "F.CrtYd")
		)
		(fp_line
			(start -1.12 -1.16)
			(end -1.12 1.15)
			(stroke
				(width 0.05)
				(type solid)
			)
			(layer "F.CrtYd")
		)
		(fp_line
			(start 0.8 0.424)
			(end -0.802 0.424)
			(stroke
				(width 0.15)
				(type solid)
			)
			(layer "F.Fab")
		)
		(fp_line
			(start 0.8 -0.425)
			(end 0.8 0.424)
			(stroke
				(width 0.15)
				(type solid)
			)
			(layer "F.Fab")
		)
		(fp_line
			(start 0.8 -0.425)
			(end -0.652 -0.425)
			(stroke
				(width 0.15)
				(type solid)
			)
			(layer "F.Fab")
		)
		(fp_line
			(start -0.652 -0.425)
			(end -0.802 -0.276)
			(stroke
				(width 0.15)
				(type solid)
			)
			(layer "F.Fab")
		)
		(fp_line
			(start -0.802 -0.276)
			(end -0.802 0.424)
			(stroke
				(width 0.15)
				(type solid)
			)
			(layer "F.Fab")
		)
		(fp_circle
			(center -0.9652 0.9652)
			(end -0.9144 0.9652)
			(stroke
				(width 0.15)
				(type solid)
			)
			(fill none)
			(layer "F.Fab")
		)
		(fp_text user "License: Apache-2.0"
			(at -1.12 5.024 180)
			(layer "F.Fab")
			(hide yes)
			(effects
				(font
					(size 0.7 0.7)
					(thickness 0.15)
				)
				(justify left bottom)
			)
		)
		(fp_text user "${REFERENCE}"
			(at -1.12 3.824 180)
			(layer "F.Fab")
			(hide yes)
			(effects
				(font
					(size 0.7 0.7)
					(thickness 0.15)
				)
				(justify left bottom)
			)
		)
		(fp_text user "Author: Antmicro"
			(at -1.12 6.224 180)
			(layer "F.Fab")
			(hide yes)
			(effects
				(font
					(size 0.7 0.7)
					(thickness 0.15)
				)
				(justify left bottom)
			)
		)
		(pad "1" smd rect
			(at -0.5 0.65 180)
			(size 0.4 0.51)
			(layers "F.Cu" "F.Paste" "F.Mask")
			(net 440 "USER_LED0")
			(pinfunction "G")
			(pintype "passive")
		)
		(pad "2" smd rect
			(at 0.498 0.65 180)
			(size 0.4 0.51)
			(layers "F.Cu" "F.Paste" "F.Mask")
			(net 1 "GND")
			(pinfunction "S")
			(pintype "passive")
		)
		(pad "3" smd rect
			(at 0 -0.652 180)
			(size 0.4 0.51)
			(layers "F.Cu" "F.Paste" "F.Mask")
			(net 164 "Net-(D26-C)")
			(pinfunction "D")
			(pintype "passive")
		)
	)
)
